# T6G (Grand Teton) — schematic netlist excerpt (pin names and nets, part order shuffled) for the footprints in the layout excerpt that follows; sources: Cadence DE-HDL packaged netlist, KiCad conversion of 04192023_DAF0TMB3IC0_F0TG_MB_C_brd_V02_OCP.brd

R4578  Q_RES  0 5% EMPTY  pkg 0402LF  page 125 : A = PRSNT_CABLE_GPU_A2_N ; B = PRSNT_CABLE_GPU_A2_ISO_N
R1069  Q_RES  4.7K 5% EMPTY  pkg 0201LF  page 298 : A = P1V8_CPU0_RT_1D ; B = GPIO2_RT_CPU0_P2
C8359  Q_CAP  1000PF 50V 5% X7R  pkg 0402  page 217 : A = PVDDCR_CPU1_P1_EN_R ; B = GND
H106  HOLE  EMPTY  pkg TH  page 230 : \1\ = GND

(kicad_pcb
	(version 20260206)
	(generator "pcbnew")
	(generator_version "10.0")
	(general
		(thickness 1.6)
		(legacy_teardrops no)
	)
	(paper "A4")
	(title_block
		(title "04192023_DAF0TMB3IC0_F0TG_MB_C_brd_V02_OCP.brd")
		(comment 1 "Grand Teton / footprints 4412-4415 of 8354")
	)
	(layers
		(0 "F.Cu" signal "TOP")
		(4 "In1.Cu" signal "GND")
		(6 "In2.Cu" signal "IN1")
		(8 "In3.Cu" signal "GND1")
		(10 "In4.Cu" signal "IN2")
		(12 "In5.Cu" signal "GND2")
		(14 "In6.Cu" signal "IN3")
		(16 "In7.Cu" signal "GND3")
		(18 "In8.Cu" signal "VCC")
		(20 "In9.Cu" signal "VCC1")
		(22 "In10.Cu" signal "GND4")
		(24 "In11.Cu" signal "IN4")
		(26 "In12.Cu" signal "GND5")
		(28 "In13.Cu" signal "IN5")
		(30 "In14.Cu" signal "GND6")
		(32 "In15.Cu" signal "IN6")
		(34 "In16.Cu" signal "GND7")
		(2 "B.Cu" signal "BOTTOM")
		(9 "F.Adhes" user "F.Adhesive")
		(11 "B.Adhes" user "B.Adhesive")
		(13 "F.Paste" user "Package Geometry/Pastemask Top")
		(15 "B.Paste" user "Package Geometry/Pastemask Bottom")
		(5 "F.SilkS" user "Ref Des/Silkscreen Top")
		(7 "B.SilkS" user "Ref Des/Silkscreen Bottom")
		(1 "F.Mask" user "Board Geometry/Soldermask Top")
		(3 "B.Mask" user "Board Geometry/Soldermask Bottom")
		(17 "Dwgs.User" user "User.Drawings")
		(19 "Cmts.User" user "User.Comments")
		(21 "Eco1.User" user "User.Eco1")
		(23 "Eco2.User" user "User.Eco2")
		(25 "Edge.Cuts" user "Board Geometry/Outline")
		(27 "Margin" user)
		(31 "F.CrtYd" user "Package Geometry/Place Bound Top")
		(29 "B.CrtYd" user "Package Geometry/Place Bound Bottom")
		(35 "F.Fab" user "Ref Des/Assembly Top")
		(33 "B.Fab" user "Ref Des/Assembly Bottom")
	)
	(footprint ""
		(layer "F.Cu")
		(at 24.765 -364.617 180)
		(property "Reference" "C8359"
			(at 0 0 180)
			(layer "F.SilkS")
			(hide yes)
			(effects
				(font
					(size 1.27 1.27)
				)
			)
		)
		(property "Value" ""
			(at 0 0 180)
			(layer "F.Fab")
			(effects
				(font
					(size 1.27 1.27)
				)
			)
		)
		(duplicate_pad_numbers_are_jumpers no)
		(fp_line
			(start 0.7874 0.4064)
			(end -0.7874 0.4064)
			(stroke
				(width 0.1524)
				(type default)
			)
			(layer "F.SilkS")
		)
		(fp_line
			(start 0.7874 -0.4064)
			(end 0.7874 0.4064)
			(stroke
				(width 0.1524)
				(type default)
			)
			(layer "F.SilkS")
		)
		(fp_line
			(start -0.7874 0.4064)
			(end -0.7874 -0.4064)
			(stroke
				(width 0.1524)
				(type default)
			)
			(layer "F.SilkS")
		)
		(fp_line
			(start -0.7874 -0.4064)
			(end 0.7874 -0.4064)
			(stroke
				(width 0.1524)
				(type default)
			)
			(layer "F.SilkS")
		)
		(fp_line
			(start 0.67945 0.3048)
			(end 0.120396 0.3048)
			(stroke
				(width 0.1)
				(type default)
			)
			(layer "F.Fab")
		)
		(fp_line
			(start 0.67945 -0.3048)
			(end 0.67945 0.3048)
			(stroke
				(width 0.1)
				(type default)
			)
			(layer "F.Fab")
		)
		(fp_line
			(start 0.12065 -0.2794)
			(end 0.12065 -0.3048)
			(stroke
				(width 0.1)
				(type default)
			)
			(layer "F.Fab")
		)
		(fp_line
			(start 0.12065 -0.3048)
			(end 0.67945 -0.3048)
			(stroke
				(width 0.1)
				(type default)
			)
			(layer "F.Fab")
		)
		(fp_line
			(start 0.120396 0.3048)
			(end 0.120396 0.2794)
			(stroke
				(width 0.1)
				(type default)
			)
			(layer "F.Fab")
		)
		(fp_line
			(start 0.120396 0.2794)
			(end -0.12065 0.2794)
			(stroke
				(width 0.1)
				(type default)
			)
			(layer "F.Fab")
		)
		(fp_line
			(start -0.12065 0.3048)
			(end -0.67945 0.3048)
			(stroke
				(width 0.1)
				(type default)
			)
			(layer "F.Fab")
		)
		(fp_line
			(start -0.12065 0.2794)
			(end -0.12065 0.3048)
			(stroke
				(width 0.1)
				(type default)
			)
			(layer "F.Fab")
		)
		(fp_line
			(start -0.12065 -0.2794)
			(end 0.12065 -0.2794)
			(stroke
				(width 0.1)
				(type default)
			)
			(layer "F.Fab")
		)
		(fp_line
			(start -0.12065 -0.305054)
			(end -0.12065 -0.2794)
			(stroke
				(width 0.1)
				(type default)
			)
			(layer "F.Fab")
		)
		(fp_line
			(start -0.67945 0.3048)
			(end -0.67945 -0.305054)
			(stroke
				(width 0.1)
				(type default)
			)
			(layer "F.Fab")
		)
		(fp_line
			(start -0.67945 -0.305054)
			(end -0.12065 -0.305054)
			(stroke
				(width 0.1)
				(type default)
			)
			(layer "F.Fab")
		)
		(pad "1" smd circle
			(at -0.40005 0 180)
			(size 0 0)
			(layers "F.Cu" "F.Mask" "F.Paste")
			(net "PVDDCR_CPU1_P1_EN_R")
		)
		(pad "2" smd circle
			(at 0.40005 0 180)
			(size 0 0)
			(layers "F.Cu" "F.Mask" "F.Paste")
			(net "GND")
		)
	)
	(footprint ""
		(layer "F.Cu")
		(at 179.749958 -435.59984)
		(property "Reference" "H106"
			(at -6.56844 -4.312412 0)
			(unlocked yes)
			(layer "F.SilkS")
			(effects
				(font
					(size 0.7874 0.5842)
					(thickness 0.1524)
				)
				(justify left)
			)
		)
		(property "Value" ""
			(at 0 0 0)
			(layer "F.Fab")
			(effects
				(font
					(size 1.27 1.27)
				)
			)
		)
		(duplicate_pad_numbers_are_jumpers no)
		(pad "1" thru_hole circle
			(at 0 0)
			(size 10.0076 10.0076)
			(drill 5.6134)
			(layers "*.Cu" "*.Mask")
			(remove_unused_layers no)
			(net "GND")
			(clearance -1.9431)
		)
	)
	(footprint ""
		(layer "F.Cu")
		(at 397.623538 -393.86256)
		(property "Reference" "R1069"
			(at 0 0 0)
			(layer "F.SilkS")
			(hide yes)
			(effects
				(font
					(size 1.27 1.27)
				)
			)
		)
		(property "Value" ""
			(at 0 0 0)
			(layer "F.Fab")
			(effects
				(font
					(size 1.27 1.27)
				)
			)
		)
		(duplicate_pad_numbers_are_jumpers no)
		(fp_line
			(start -0.32512 -0.175006)
			(end 0.32512 -0.175006)
			(stroke
				(width 0.1)
				(type default)
			)
			(layer "F.Fab")
		)
		(fp_line
			(start -0.32512 0.175006)
			(end -0.32512 -0.175006)
			(stroke
				(width 0.1)
				(type default)
			)
			(layer "F.Fab")
		)
		(fp_line
			(start 0.32512 -0.175006)
			(end 0.32512 0.175006)
			(stroke
				(width 0.1)
				(type default)
			)
			(layer "F.Fab")
		)
		(fp_line
			(start 0.32512 0.175006)
			(end -0.32512 0.175006)
			(stroke
				(width 0.1)
				(type default)
			)
			(layer "F.Fab")
		)
		(pad "1" smd rect
			(at -0.2667 0)
			(size 0.3048 0.381)
			(layers "F.Cu" "F.Mask" "F.Paste")
			(net "P1V8_CPU0_RT_1D")
		)
		(pad "2" smd rect
			(at 0.2667 0 180)
			(size 0.3048 0.381)
			(layers "F.Cu" "F.Mask" "F.Paste")
			(net "GPIO2_RT_CPU0_P2")
		)
	)
	(footprint ""
		(layer "F.Cu")
		(at 307.220366 -429.224186 180)
		(property "Reference" "R4578"
			(at 0 0 180)
			(layer "F.SilkS")
			(hide yes)
			(effects
				(font
					(size 1.27 1.27)
				)
			)
		)
		(property "Value" ""
			(at 0 0 180)
			(layer "F.Fab")
			(effects
				(font
					(size 1.27 1.27)
				)
			)
		)
		(duplicate_pad_numbers_are_jumpers no)
		(fp_line
			(start 0.7874 0.4064)
			(end -0.7874 0.4064)
			(stroke
				(width 0.1524)
				(type default)
			)
			(layer "F.SilkS")
		)
		(fp_line
			(start 0.7874 -0.4064)
			(end 0.7874 0.4064)
			(stroke
				(width 0.1524)
				(type default)
			)
			(layer "F.SilkS")
		)
		(fp_line
			(start -0.7874 0.4064)
			(end -0.7874 -0.4064)
			(stroke
				(width 0.1524)
				(type default)
			)
			(layer "F.SilkS")
		)
		(fp_line
			(start -0.7874 -0.4064)
			(end 0.7874 -0.4064)
			(stroke
				(width 0.1524)
				(type default)
			)
			(layer "F.SilkS")
		)
		(fp_line
			(start 0.67945 0.3048)
			(end 0.120396 0.3048)
			(stroke
				(width 0.1)
				(type default)
			)
			(layer "F.Fab")
		)
		(fp_line
			(start 0.67945 -0.3048)
			(end 0.67945 0.3048)
			(stroke
				(width 0.1)
				(type default)
			)
			(layer "F.Fab")
		)
		(fp_line
			(start 0.12065 -0.2794)
			(end 0.12065 -0.3048)
			(stroke
				(width 0.1)
				(type default)
			)
			(layer "F.Fab")
		)
		(fp_line
			(start 0.12065 -0.3048)
			(end 0.67945 -0.3048)
			(stroke
				(width 0.1)
				(type default)
			)
			(layer "F.Fab")
		)
		(fp_line
			(start 0.120396 0.3048)
			(end 0.120396 0.2794)
			(stroke
				(width 0.1)
				(type default)
			)
			(layer "F.Fab")
		)
		(fp_line
			(start 0.120396 0.2794)
			(end -0.12065 0.2794)
			(stroke
				(width 0.1)
				(type default)
			)
			(layer "F.Fab")
		)
		(fp_line
			(start -0.12065 0.3048)
			(end -0.67945 0.3048)
			(stroke
				(width 0.1)
				(type default)
			)
			(layer "F.Fab")
		)
		(fp_line
			(start -0.12065 0.2794)
			(end -0.12065 0.3048)
			(stroke
				(width 0.1)
				(type default)
			)
			(layer "F.Fab")
		)
		(fp_line
			(start -0.12065 -0.2794)
			(end 0.12065 -0.2794)
			(stroke
				(width 0.1)
				(type default)
			)
			(layer "F.Fab")
		)
		(fp_line
			(start -0.12065 -0.305054)
			(end -0.12065 -0.2794)
			(stroke
				(width 0.1)
				(type default)
			)
			(layer "F.Fab")
		)
		(fp_line
			(start -0.67945 0.3048)
			(end -0.67945 -0.305054)
			(stroke
				(width 0.1)
				(type default)
			)
			(layer "F.Fab")
		)
		(fp_line
			(start -0.67945 -0.305054)
			(end -0.12065 -0.305054)
			(stroke
				(width 0.1)
				(type default)
			)
			(layer "F.Fab")
		)
		(pad "1" smd circle
			(at -0.40005 0 180)
			(size 0 0)
			(layers "F.Cu" "F.Mask" "F.Paste")
			(net "PRSNT_CABLE_GPU_A2_N")
		)
		(pad "2" smd circle
			(at 0.40005 0 180)
			(size 0 0)
			(layers "F.Cu" "F.Mask" "F.Paste")
			(net "PRSNT_CABLE_GPU_A2_ISO_N")
		)
	)
)
